(kicad_pcb
	(version 20260206)
	(generator "pcbnew")
	(generator_version "10.0")
	(general
		(thickness 1.6)
		(legacy_teardrops no)
	)
	(paper "A4")
	(title_block
		(title "04192023_DAF0TMB3IC0_F0TG_MB_C_brd_V02_OCP.brd")
		(comment 1 "Grand Teton / footprints 5937-5942 of 8354")
	)
	(layers
		(0 "F.Cu" signal "TOP")
		(4 "In1.Cu" signal "GND")
		(6 "In2.Cu" signal "IN1")
		(8 "In3.Cu" signal "GND1")
		(10 "In4.Cu" signal "IN2")
		(12 "In5.Cu" signal "GND2")
		(14 "In6.Cu" signal "IN3")
		(16 "In7.Cu" signal "GND3")
		(18 "In8.Cu" signal "VCC")
		(20 "In9.Cu" signal "VCC1")
		(22 "In10.Cu" signal "GND4")
		(24 "In11.Cu" signal "IN4")
		(26 "In12.Cu" signal "GND5")
		(28 "In13.Cu" signal "IN5")
		(30 "In14.Cu" signal "GND6")
		(32 "In15.Cu" signal "IN6")
		(34 "In16.Cu" signal "GND7")
		(2 "B.Cu" signal "BOTTOM")
		(9 "F.Adhes" user "F.Adhesive")
		(11 "B.Adhes" user "B.Adhesive")
		(13 "F.Paste" user "Package Geometry/Pastemask Top")
		(15 "B.Paste" user "Package Geometry/Pastemask Bottom")
		(5 "F.SilkS" user "Ref Des/Silkscreen Top")
		(7 "B.SilkS" user "Ref Des/Silkscreen Bottom")
		(1 "F.Mask" user "Board Geometry/Soldermask Top")
		(3 "B.Mask" user "Board Geometry/Soldermask Bottom")
		(17 "Dwgs.User" user "User.Drawings")
		(19 "Cmts.User" user "User.Comments")
		(21 "Eco1.User" user "User.Eco1")
		(23 "Eco2.User" user "User.Eco2")
		(25 "Edge.Cuts" user "Board Geometry/Outline")
		(27 "Margin" user)
		(31 "F.CrtYd" user "Package Geometry/Place Bound Top")
		(29 "B.CrtYd" user "Package Geometry/Place Bound Bottom")
		(35 "F.Fab" user "Ref Des/Assembly Top")
		(33 "B.Fab" user "Ref Des/Assembly Bottom")
	)
	(footprint ""
		(layer "B.Cu")
		(at 69.861684 -391.81405 180)
		(property "Reference" "C220"
			(at 0 0 0)
			(layer "B.SilkS")
			(hide yes)
			(effects
				(font
					(size 1.27 1.27)
				)
				(justify mirror)
			)
		)
		(property "Value" ""
			(at 0 0 0)
			(layer "B.Fab")
			(effects
				(font
					(size 1.27 1.27)
				)
				(justify mirror)
			)
		)
		(duplicate_pad_numbers_are_jumpers no)
		(fp_line
			(start 1.524 0.762)
			(end 1.524 -0.762)
			(stroke
				(width 0.1524)
				(type default)
			)
			(layer "B.SilkS")
		)
		(fp_line
			(start 1.524 -0.762)
			(end -1.524 -0.762)
			(stroke
				(width 0.1524)
				(type default)
			)
			(layer "B.SilkS")
		)
		(fp_line
			(start -1.524 0.762)
			(end 1.524 0.762)
			(stroke
				(width 0.1524)
				(type default)
			)
			(layer "B.SilkS")
		)
		(fp_line
			(start -1.524 -0.762)
			(end -1.524 0.762)
			(stroke
				(width 0.1524)
				(type default)
			)
			(layer "B.SilkS")
		)
		(fp_line
			(start 1.1049 0.724916)
			(end -1.1049 0.724916)
			(stroke
				(width 0.1)
				(type default)
			)
			(layer "B.Fab")
		)
		(fp_line
			(start 1.1049 -0.724916)
			(end 1.1049 0.724916)
			(stroke
				(width 0.1)
				(type default)
			)
			(layer "B.Fab")
		)
		(fp_line
			(start -1.1049 0.724916)
			(end -1.1049 -0.724916)
			(stroke
				(width 0.1)
				(type default)
			)
			(layer "B.Fab")
		)
		(fp_line
			(start -1.1049 -0.724916)
			(end 1.1049 -0.724916)
			(stroke
				(width 0.1)
				(type default)
			)
			(layer "B.Fab")
		)
		(pad "1" smd rect
			(at 0.889 0 180)
			(size 1.016 1.27)
			(layers "B.Cu" "B.Mask" "B.Paste")
			(net "P0V9_CPU1_RT0_2A")
		)
		(pad "2" smd rect
			(at -0.889 0 180)
			(size 1.016 1.27)
			(layers "B.Cu" "B.Mask" "B.Paste")
			(net "GND")
		)
	)
	(footprint ""
		(layer "B.Cu")
		(at 430.55921 -244.08511)
		(property "Reference" "R383"
			(at 0 0 0)
			(layer "B.SilkS")
			(hide yes)
			(effects
				(font
					(size 1.27 1.27)
				)
				(justify mirror)
			)
		)
		(property "Value" ""
			(at 0 0 0)
			(layer "B.Fab")
			(effects
				(font
					(size 1.27 1.27)
				)
				(justify mirror)
			)
		)
		(duplicate_pad_numbers_are_jumpers no)
		(fp_line
			(start -0.7874 -0.4064)
			(end -0.7874 0.4064)
			(stroke
				(width 0.1524)
				(type default)
			)
			(layer "B.SilkS")
		)
		(fp_line
			(start -0.7874 0.4064)
			(end 0.7874 0.4064)
			(stroke
				(width 0.1524)
				(type default)
			)
			(layer "B.SilkS")
		)
		(fp_line
			(start 0.7874 -0.4064)
			(end -0.7874 -0.4064)
			(stroke
				(width 0.1524)
				(type default)
			)
			(layer "B.SilkS")
		)
		(fp_line
			(start 0.7874 0.4064)
			(end 0.7874 -0.4064)
			(stroke
				(width 0.1524)
				(type default)
			)
			(layer "B.SilkS")
		)
		(fp_line
			(start -0.67945 -0.3048)
			(end -0.67945 0.3048)
			(stroke
				(width 0.1)
				(type default)
			)
			(layer "B.Fab")
		)
		(fp_line
			(start -0.67945 0.3048)
			(end -0.120396 0.3048)
			(stroke
				(width 0.1)
				(type default)
			)
			(layer "B.Fab")
		)
		(fp_line
			(start -0.12065 -0.3048)
			(end -0.67945 -0.3048)
			(stroke
				(width 0.1)
				(type default)
			)
			(layer "B.Fab")
		)
		(fp_line
			(start -0.12065 -0.2794)
			(end -0.12065 -0.3048)
			(stroke
				(width 0.1)
				(type default)
			)
			(layer "B.Fab")
		)
		(fp_line
			(start -0.120396 0.2794)
			(end 0.12065 0.2794)
			(stroke
				(width 0.1)
				(type default)
			)
			(layer "B.Fab")
		)
		(fp_line
			(start -0.120396 0.3048)
			(end -0.120396 0.2794)
			(stroke
				(width 0.1)
				(type default)
			)
			(layer "B.Fab")
		)
		(fp_line
			(start 0.12065 -0.305054)
			(end 0.12065 -0.2794)
			(stroke
				(width 0.1)
				(type default)
			)
			(layer "B.Fab")
		)
		(fp_line
			(start 0.12065 -0.2794)
			(end -0.12065 -0.2794)
			(stroke
				(width 0.1)
				(type default)
			)
			(layer "B.Fab")
		)
		(fp_line
			(start 0.12065 0.2794)
			(end 0.12065 0.3048)
			(stroke
				(width 0.1)
				(type default)
			)
			(layer "B.Fab")
		)
		(fp_line
			(start 0.12065 0.3048)
			(end 0.67945 0.3048)
			(stroke
				(width 0.1)
				(type default)
			)
			(layer "B.Fab")
		)
		(fp_line
			(start 0.67945 -0.305054)
			(end 0.12065 -0.305054)
			(stroke
				(width 0.1)
				(type default)
			)
			(layer "B.Fab")
		)
		(fp_line
			(start 0.67945 0.3048)
			(end 0.67945 -0.305054)
			(stroke
				(width 0.1)
				(type default)
			)
			(layer "B.Fab")
		)
		(pad "1" smd circle
			(at 0.40005 0 180)
			(size 0 0)
			(layers "B.Cu" "B.Mask" "B.Paste")
			(net "M_I_CPU0_ALERT_N")
		)
		(pad "2" smd circle
			(at -0.40005 0 180)
			(size 0 0)
			(layers "B.Cu" "B.Mask" "B.Paste")
			(net "M_I_CPU0_ALERT_R_N")
		)
	)
	(footprint ""
		(layer "B.Cu")
		(at 372.313454 -261.046976)
		(property "Reference" "C2548"
			(at 0 0 0)
			(layer "B.SilkS")
			(hide yes)
			(effects
				(font
					(size 1.27 1.27)
				)
				(justify mirror)
			)
		)
		(property "Value" ""
			(at 0 0 0)
			(layer "B.Fab")
			(effects
				(font
					(size 1.27 1.27)
				)
				(justify mirror)
			)
		)
		(duplicate_pad_numbers_are_jumpers no)
		(fp_line
			(start -0.7874 -0.4064)
			(end -0.7874 0.4064)
			(stroke
				(width 0.1524)
				(type default)
			)
			(layer "B.SilkS")
		)
		(fp_line
			(start -0.7874 0.4064)
			(end 0.7874 0.4064)
			(stroke
				(width 0.1524)
				(type default)
			)
			(layer "B.SilkS")
		)
		(fp_line
			(start 0.7874 -0.4064)
			(end -0.7874 -0.4064)
			(stroke
				(width 0.1524)
				(type default)
			)
			(layer "B.SilkS")
		)
		(fp_line
			(start 0.7874 0.4064)
			(end 0.7874 -0.4064)
			(stroke
				(width 0.1524)
				(type default)
			)
			(layer "B.SilkS")
		)
		(fp_line
			(start -0.67945 -0.3048)
			(end -0.67945 0.3048)
			(stroke
				(width 0.1)
				(type default)
			)
			(layer "B.Fab")
		)
		(fp_line
			(start -0.67945 0.3048)
			(end -0.120396 0.3048)
			(stroke
				(width 0.1)
				(type default)
			)
			(layer "B.Fab")
		)
		(fp_line
			(start -0.12065 -0.3048)
			(end -0.67945 -0.3048)
			(stroke
				(width 0.1)
				(type default)
			)
			(layer "B.Fab")
		)
		(fp_line
			(start -0.12065 -0.2794)
			(end -0.12065 -0.3048)
			(stroke
				(width 0.1)
				(type default)
			)
			(layer "B.Fab")
		)
		(fp_line
			(start -0.120396 0.2794)
			(end 0.12065 0.2794)
			(stroke
				(width 0.1)
				(type default)
			)
			(layer "B.Fab")
		)
		(fp_line
			(start -0.120396 0.3048)
			(end -0.120396 0.2794)
			(stroke
				(width 0.1)
				(type default)
			)
			(layer "B.Fab")
		)
		(fp_line
			(start 0.12065 -0.305054)
			(end 0.12065 -0.2794)
			(stroke
				(width 0.1)
				(type default)
			)
			(layer "B.Fab")
		)
		(fp_line
			(start 0.12065 -0.2794)
			(end -0.12065 -0.2794)
			(stroke
				(width 0.1)
				(type default)
			)
			(layer "B.Fab")
		)
		(fp_line
			(start 0.12065 0.2794)
			(end 0.12065 0.3048)
			(stroke
				(width 0.1)
				(type default)
			)
			(layer "B.Fab")
		)
		(fp_line
			(start 0.12065 0.3048)
			(end 0.67945 0.3048)
			(stroke
				(width 0.1)
				(type default)
			)
			(layer "B.Fab")
		)
		(fp_line
			(start 0.67945 -0.305054)
			(end 0.12065 -0.305054)
			(stroke
				(width 0.1)
				(type default)
			)
			(layer "B.Fab")
		)
		(fp_line
			(start 0.67945 0.3048)
			(end 0.67945 -0.305054)
			(stroke
				(width 0.1)
				(type default)
			)
			(layer "B.Fab")
		)
		(pad "1" smd circle
			(at 0.40005 0 180)
			(size 0 0)
			(layers "B.Cu" "B.Mask" "B.Paste")
			(net "PVDDCR_SOC_P0")
		)
		(pad "2" smd circle
			(at -0.40005 0 180)
			(size 0 0)
			(layers "B.Cu" "B.Mask" "B.Paste")
			(net "GND")
		)
	)
	(footprint ""
		(layer "B.Cu")
		(at 356.311454 -266.00531)
		(property "Reference" "C3890"
			(at 0 0 0)
			(layer "B.SilkS")
			(hide yes)
			(effects
				(font
					(size 1.27 1.27)
				)
				(justify mirror)
			)
		)
		(property "Value" ""
			(at 0 0 0)
			(layer "B.Fab")
			(effects
				(font
					(size 1.27 1.27)
				)
				(justify mirror)
			)
		)
		(duplicate_pad_numbers_are_jumpers no)
		(fp_line
			(start -0.7874 -0.4064)
			(end -0.7874 0.4064)
			(stroke
				(width 0.1524)
				(type default)
			)
			(layer "B.SilkS")
		)
		(fp_line
			(start -0.7874 0.4064)
			(end 0.7874 0.4064)
			(stroke
				(width 0.1524)
				(type default)
			)
			(layer "B.SilkS")
		)
		(fp_line
			(start 0.7874 -0.4064)
			(end -0.7874 -0.4064)
			(stroke
				(width 0.1524)
				(type default)
			)
			(layer "B.SilkS")
		)
		(fp_line
			(start 0.7874 0.4064)
			(end 0.7874 -0.4064)
			(stroke
				(width 0.1524)
				(type default)
			)
			(layer "B.SilkS")
		)
		(fp_line
			(start -0.67945 -0.3048)
			(end -0.67945 0.3048)
			(stroke
				(width 0.1)
				(type default)
			)
			(layer "B.Fab")
		)
		(fp_line
			(start -0.67945 0.3048)
			(end -0.120396 0.3048)
			(stroke
				(width 0.1)
				(type default)
			)
			(layer "B.Fab")
		)
		(fp_line
			(start -0.12065 -0.3048)
			(end -0.67945 -0.3048)
			(stroke
				(width 0.1)
				(type default)
			)
			(layer "B.Fab")
		)
		(fp_line
			(start -0.12065 -0.2794)
			(end -0.12065 -0.3048)
			(stroke
				(width 0.1)
				(type default)
			)
			(layer "B.Fab")
		)
		(fp_line
			(start -0.120396 0.2794)
			(end 0.12065 0.2794)
			(stroke
				(width 0.1)
				(type default)
			)
			(layer "B.Fab")
		)
		(fp_line
			(start -0.120396 0.3048)
			(end -0.120396 0.2794)
			(stroke
				(width 0.1)
				(type default)
			)
			(layer "B.Fab")
		)
		(fp_line
			(start 0.12065 -0.305054)
			(end 0.12065 -0.2794)
			(stroke
				(width 0.1)
				(type default)
			)
			(layer "B.Fab")
		)
		(fp_line
			(start 0.12065 -0.2794)
			(end -0.12065 -0.2794)
			(stroke
				(width 0.1)
				(type default)
			)
			(layer "B.Fab")
		)
		(fp_line
			(start 0.12065 0.2794)
			(end 0.12065 0.3048)
			(stroke
				(width 0.1)
				(type default)
			)
			(layer "B.Fab")
		)
		(fp_line
			(start 0.12065 0.3048)
			(end 0.67945 0.3048)
			(stroke
				(width 0.1)
				(type default)
			)
			(layer "B.Fab")
		)
		(fp_line
			(start 0.67945 -0.305054)
			(end 0.12065 -0.305054)
			(stroke
				(width 0.1)
				(type default)
			)
			(layer "B.Fab")
		)
		(fp_line
			(start 0.67945 0.3048)
			(end 0.67945 -0.305054)
			(stroke
				(width 0.1)
				(type default)
			)
			(layer "B.Fab")
		)
		(pad "1" smd circle
			(at 0.40005 0 180)
			(size 0 0)
			(layers "B.Cu" "B.Mask" "B.Paste")
			(net "PVDD11_S3_P0")
		)
		(pad "2" smd circle
			(at -0.40005 0 180)
			(size 0 0)
			(layers "B.Cu" "B.Mask" "B.Paste")
			(net "GND")
		)
	)
	(footprint ""
		(layer "B.Cu")
		(at 119.291354 -390.560052 90)
		(property "Reference" "C487"
			(at 0 0 90)
			(layer "B.SilkS")
			(hide yes)
			(effects
				(font
					(size 1.27 1.27)
				)
				(justify mirror)
			)
		)
		(property "Value" ""
			(at 0 0 90)
			(layer "B.Fab")
			(effects
				(font
					(size 1.27 1.27)
				)
				(justify mirror)
			)
		)
		(duplicate_pad_numbers_are_jumpers no)
		(fp_line
			(start 0.7874 -0.4064)
			(end -0.7874 -0.4064)
			(stroke
				(width 0.1524)
				(type default)
			)
			(layer "B.SilkS")
		)
		(fp_line
			(start -0.7874 -0.4064)
			(end -0.7874 0.4064)
			(stroke
				(width 0.1524)
				(type default)
			)
			(layer "B.SilkS")
		)
		(fp_line
			(start 0.7874 0.4064)
			(end 0.7874 -0.4064)
			(stroke
				(width 0.1524)
				(type default)
			)
			(layer "B.SilkS")
		)
		(fp_line
			(start -0.7874 0.4064)
			(end 0.7874 0.4064)
			(stroke
				(width 0.1524)
				(type default)
			)
			(layer "B.SilkS")
		)
		(fp_line
			(start 0.67945 -0.305054)
			(end 0.12065 -0.305054)
			(stroke
				(width 0.1)
				(type default)
			)
			(layer "B.Fab")
		)
		(fp_line
			(start 0.12065 -0.305054)
			(end 0.12065 -0.2794)
			(stroke
				(width 0.1)
				(type default)
			)
			(layer "B.Fab")
		)
		(fp_line
			(start -0.12065 -0.3048)
			(end -0.67945 -0.3048)
			(stroke
				(width 0.1)
				(type default)
			)
			(layer "B.Fab")
		)
		(fp_line
			(start -0.67945 -0.3048)
			(end -0.67945 0.3048)
			(stroke
				(width 0.1)
				(type default)
			)
			(layer "B.Fab")
		)
		(fp_line
			(start 0.12065 -0.2794)
			(end -0.12065 -0.2794)
			(stroke
				(width 0.1)
				(type default)
			)
			(layer "B.Fab")
		)
		(fp_line
			(start -0.12065 -0.2794)
			(end -0.12065 -0.3048)
			(stroke
				(width 0.1)
				(type default)
			)
			(layer "B.Fab")
		)
		(fp_line
			(start 0.12065 0.2794)
			(end 0.12065 0.3048)
			(stroke
				(width 0.1)
				(type default)
			)
			(layer "B.Fab")
		)
		(fp_line
			(start -0.120396 0.2794)
			(end 0.12065 0.2794)
			(stroke
				(width 0.1)
				(type default)
			)
			(layer "B.Fab")
		)
		(fp_line
			(start 0.67945 0.3048)
			(end 0.67945 -0.305054)
			(stroke
				(width 0.1)
				(type default)
			)
			(layer "B.Fab")
		)
		(fp_line
			(start 0.12065 0.3048)
			(end 0.67945 0.3048)
			(stroke
				(width 0.1)
				(type default)
			)
			(layer "B.Fab")
		)
		(fp_line
			(start -0.120396 0.3048)
			(end -0.120396 0.2794)
			(stroke
				(width 0.1)
				(type default)
			)
			(layer "B.Fab")
		)
		(fp_line
			(start -0.67945 0.3048)
			(end -0.120396 0.3048)
			(stroke
				(width 0.1)
				(type default)
			)
			(layer "B.Fab")
		)
		(pad "1" smd circle
			(at 0.40005 0 270)
			(size 0 0)
			(layers "B.Cu" "B.Mask" "B.Paste")
			(net "P0V9_CPU1_RT3_2A")
		)
		(pad "2" smd circle
			(at -0.40005 0 270)
			(size 0 0)
			(layers "B.Cu" "B.Mask" "B.Paste")
			(net "GND")
		)
	)
	(footprint ""
		(layer "B.Cu")
		(at 106.212386 -251.781564)
		(property "Reference" "C2448"
			(at 0 0 0)
			(layer "B.SilkS")
			(hide yes)
			(effects
				(font
					(size 1.27 1.27)
				)
				(justify mirror)
			)
		)
		(property "Value" ""
			(at 0 0 0)
			(layer "B.Fab")
			(effects
				(font
					(size 1.27 1.27)
				)
				(justify mirror)
			)
		)
		(duplicate_pad_numbers_are_jumpers no)
		(fp_line
			(start -0.7874 -0.4064)
			(end -0.7874 0.4064)
			(stroke
				(width 0.1524)
				(type default)
			)
			(layer "B.SilkS")
		)
		(fp_line
			(start -0.7874 0.4064)
			(end 0.7874 0.4064)
			(stroke
				(width 0.1524)
				(type default)
			)
			(layer "B.SilkS")
		)
		(fp_line
			(start 0.7874 -0.4064)
			(end -0.7874 -0.4064)
			(stroke
				(width 0.1524)
				(type default)
			)
			(layer "B.SilkS")
		)
		(fp_line
			(start 0.7874 0.4064)
			(end 0.7874 -0.4064)
			(stroke
				(width 0.1524)
				(type default)
			)
			(layer "B.SilkS")
		)
		(fp_line
			(start -0.67945 -0.3048)
			(end -0.67945 0.3048)
			(stroke
				(width 0.1)
				(type default)
			)
			(layer "B.Fab")
		)
		(fp_line
			(start -0.67945 0.3048)
			(end -0.120396 0.3048)
			(stroke
				(width 0.1)
				(type default)
			)
			(layer "B.Fab")
		)
		(fp_line
			(start -0.12065 -0.3048)
			(end -0.67945 -0.3048)
			(stroke
				(width 0.1)
				(type default)
			)
			(layer "B.Fab")
		)
		(fp_line
			(start -0.12065 -0.2794)
			(end -0.12065 -0.3048)
			(stroke
				(width 0.1)
				(type default)
			)
			(layer "B.Fab")
		)
		(fp_line
			(start -0.120396 0.2794)
			(end 0.12065 0.2794)
			(stroke
				(width 0.1)
				(type default)
			)
			(layer "B.Fab")
		)
		(fp_line
			(start -0.120396 0.3048)
			(end -0.120396 0.2794)
			(stroke
				(width 0.1)
				(type default)
			)
			(layer "B.Fab")
		)
		(fp_line
			(start 0.12065 -0.305054)
			(end 0.12065 -0.2794)
			(stroke
				(width 0.1)
				(type default)
			)
			(layer "B.Fab")
		)
		(fp_line
			(start 0.12065 -0.2794)
			(end -0.12065 -0.2794)
			(stroke
				(width 0.1)
				(type default)
			)
			(layer "B.Fab")
		)
		(fp_line
			(start 0.12065 0.2794)
			(end 0.12065 0.3048)
			(stroke
				(width 0.1)
				(type default)
			)
			(layer "B.Fab")
		)
		(fp_line
			(start 0.12065 0.3048)
			(end 0.67945 0.3048)
			(stroke
				(width 0.1)
				(type default)
			)
			(layer "B.Fab")
		)
		(fp_line
			(start 0.67945 -0.305054)
			(end 0.12065 -0.305054)
			(stroke
				(width 0.1)
				(type default)
			)
			(layer "B.Fab")
		)
		(fp_line
			(start 0.67945 0.3048)
			(end 0.67945 -0.305054)
			(stroke
				(width 0.1)
				(type default)
			)
			(layer "B.Fab")
		)
		(pad "1" smd circle
			(at 0.40005 0 180)
			(size 0 0)
			(layers "B.Cu" "B.Mask" "B.Paste")
			(net "PVDDCR_SOC_P1")
		)
		(pad "2" smd circle
			(at -0.40005 0 180)
			(size 0 0)
			(layers "B.Cu" "B.Mask" "B.Paste")
			(net "GND")
		)
	)
)
